(kicad_pcb
	(version 20260206)
	(generator "pcbnew")
	(generator_version "10.0")
	(general
		(thickness 1.6)
		(legacy_teardrops no)
	)
	(paper "A4")
	(title_block
		(title "Bryce Canyon_SCC_16316-1_OCP.brd")
		(comment 1 "Bryce Canyon / footprints 467-473 of 1561")
	)
	(layers
		(0 "F.Cu" signal "TOP")
		(4 "In1.Cu" signal "L2GND")
		(6 "In2.Cu" signal "L3")
		(8 "In3.Cu" signal "L4VCC")
		(10 "In4.Cu" signal "L5VCC")
		(12 "In5.Cu" signal "L6")
		(14 "In6.Cu" signal "L7GND")
		(2 "B.Cu" signal "BOTTOM")
		(9 "F.Adhes" user "F.Adhesive")
		(11 "B.Adhes" user "B.Adhesive")
		(13 "F.Paste" user "Package Geometry/Pastemask Top")
		(15 "B.Paste" user "Package Geometry/Pastemask Bottom")
		(5 "F.SilkS" user "Ref Des/Silkscreen Top")
		(7 "B.SilkS" user "Ref Des/Silkscreen Bottom")
		(1 "F.Mask" user "Board Geometry/Soldermask Top")
		(3 "B.Mask" user "Board Geometry/Soldermask Bottom")
		(17 "Dwgs.User" user "User.Drawings")
		(19 "Cmts.User" user "User.Comments")
		(21 "Eco1.User" user "User.Eco1")
		(23 "Eco2.User" user "User.Eco2")
		(25 "Edge.Cuts" user "Board Geometry/Outline")
		(27 "Margin" user)
		(31 "F.CrtYd" user "Package Geometry/Place Bound Top")
		(29 "B.CrtYd" user "Package Geometry/Place Bound Bottom")
		(35 "F.Fab" user "Ref Des/Assembly Top")
		(33 "B.Fab" user "Ref Des/Assembly Bottom")
	)
	(footprint ""
		(layer "F.Cu")
		(at 86.9315 -78.695042 -90)
		(property "Reference" "R150"
			(at 0 0 270)
			(layer "F.SilkS")
			(hide yes)
			(effects
				(font
					(size 1.27 1.27)
				)
			)
		)
		(property "Value" "4K75R2F-1-GP"
			(at 0.064008 -3.993896 270)
			(unlocked yes)
			(layer "F.Fab")
			(hide yes)
			(effects
				(font
					(size 1.016 1.016)
					(thickness 0.1524)
				)
			)
		)
		(property "Device Type" "R402H16"
			(at 0.064008 -5.517896 270)
			(unlocked yes)
			(layer "F.Fab")
			(hide yes)
			(effects
				(font
					(size 1.016 1.016)
					(thickness 0.1524)
				)
			)
		)
		(duplicate_pad_numbers_are_jumpers no)
		(fp_line
			(start -0.508 -0.9398)
			(end -0.508 0.9398)
			(stroke
				(width 0.1524)
				(type default)
			)
			(layer "F.SilkS")
		)
		(fp_line
			(start 0.508 -0.9398)
			(end -0.508 -0.9398)
			(stroke
				(width 0.1524)
				(type default)
			)
			(layer "F.SilkS")
		)
		(fp_rect
			(start -0.508 0.9398)
			(end 0.508 -0.9398)
			(stroke
				(width 0)
				(type default)
			)
			(fill no)
			(layer "F.CrtYd")
		)
		(fp_rect
			(start -0.508 0.9398)
			(end 0.508 -0.9398)
			(stroke
				(width 0)
				(type default)
			)
			(fill no)
			(layer "F.Fab")
		)
		(pad "1" smd custom
			(at 0 -0.4445 270)
			(size 0.1397 0.1397)
			(layers "F.Cu" "F.Mask" "F.Paste")
			(net "P1V8_E")
			(options
				(clearance outline)
				(anchor circle)
			)
			(primitives
				(gr_poly
					(pts
						(arc
							(start -0.1778 -0.2794)
							(mid -0.249642 -0.249642)
							(end -0.2794 -0.1778)
						)
						(arc
							(start -0.2794 0.1778)
							(mid -0.249642 0.249642)
							(end -0.1778 0.2794)
						)
						(arc
							(start 0.1778 0.2794)
							(mid 0.249642 0.249642)
							(end 0.2794 0.1778)
						)
						(arc
							(start 0.2794 -0.1778)
							(mid 0.249642 -0.249642)
							(end 0.1778 -0.2794)
						)
					)
					(width 0)
					(fill yes)
				)
			)
		)
		(pad "2" smd custom
			(at 0 0.4445 270)
			(size 0.1397 0.1397)
			(layers "F.Cu" "F.Mask" "F.Paste")
			(net "EXP_XM_NOR_CS_N")
			(options
				(clearance outline)
				(anchor circle)
			)
			(primitives
				(gr_poly
					(pts
						(arc
							(start -0.1778 -0.2794)
							(mid -0.249642 -0.249642)
							(end -0.2794 -0.1778)
						)
						(arc
							(start -0.2794 0.1778)
							(mid -0.249642 0.249642)
							(end -0.1778 0.2794)
						)
						(arc
							(start 0.1778 0.2794)
							(mid 0.249642 0.249642)
							(end 0.2794 0.1778)
						)
						(arc
							(start 0.2794 -0.1778)
							(mid 0.249642 -0.249642)
							(end 0.1778 -0.2794)
						)
					)
					(width 0)
					(fill yes)
				)
			)
		)
	)
	(footprint ""
		(layer "F.Cu")
		(at 159.722312 -97.867216 90)
		(property "Reference" "R291"
			(at 0 0 90)
			(layer "F.SilkS")
			(hide yes)
			(effects
				(font
					(size 1.27 1.27)
				)
			)
		)
		(property "Value" "10KR2F-2-GP"
			(at 0.064008 -3.993896 90)
			(unlocked yes)
			(layer "F.Fab")
			(hide yes)
			(effects
				(font
					(size 1.016 1.016)
					(thickness 0.1524)
				)
			)
		)
		(property "Device Type" "R402H16"
			(at 0.064008 -5.517896 90)
			(unlocked yes)
			(layer "F.Fab")
			(hide yes)
			(effects
				(font
					(size 1.016 1.016)
					(thickness 0.1524)
				)
			)
		)
		(duplicate_pad_numbers_are_jumpers no)
		(fp_line
			(start 0.508 -0.9398)
			(end -0.508 -0.9398)
			(stroke
				(width 0.1524)
				(type default)
			)
			(layer "F.SilkS")
		)
		(fp_line
			(start -0.508 -0.9398)
			(end -0.508 0.9398)
			(stroke
				(width 0.1524)
				(type default)
			)
			(layer "F.SilkS")
		)
		(fp_rect
			(start -0.508 0.9398)
			(end 0.508 -0.9398)
			(stroke
				(width 0)
				(type default)
			)
			(fill no)
			(layer "F.CrtYd")
		)
		(fp_rect
			(start -0.508 0.9398)
			(end 0.508 -0.9398)
			(stroke
				(width 0)
				(type default)
			)
			(fill no)
			(layer "F.Fab")
		)
		(pad "1" smd custom
			(at 0 -0.4445 90)
			(size 0.1397 0.1397)
			(layers "F.Cu" "F.Mask" "F.Paste")
			(net "SDB_UART_EN")
			(options
				(clearance outline)
				(anchor circle)
			)
			(primitives
				(gr_poly
					(pts
						(arc
							(start -0.1778 -0.2794)
							(mid -0.249642 -0.249642)
							(end -0.2794 -0.1778)
						)
						(arc
							(start -0.2794 0.1778)
							(mid -0.249642 0.249642)
							(end -0.1778 0.2794)
						)
						(arc
							(start 0.1778 0.2794)
							(mid 0.249642 0.249642)
							(end 0.2794 0.1778)
						)
						(arc
							(start 0.2794 -0.1778)
							(mid 0.249642 -0.249642)
							(end 0.1778 -0.2794)
						)
					)
					(width 0)
					(fill yes)
				)
			)
		)
		(pad "2" smd custom
			(at 0 0.4445 90)
			(size 0.1397 0.1397)
			(layers "F.Cu" "F.Mask" "F.Paste")
			(net "P1V8_E")
			(options
				(clearance outline)
				(anchor circle)
			)
			(primitives
				(gr_poly
					(pts
						(arc
							(start -0.1778 -0.2794)
							(mid -0.249642 -0.249642)
							(end -0.2794 -0.1778)
						)
						(arc
							(start -0.2794 0.1778)
							(mid -0.249642 0.249642)
							(end -0.1778 0.2794)
						)
						(arc
							(start 0.1778 0.2794)
							(mid 0.249642 0.249642)
							(end 0.2794 0.1778)
						)
						(arc
							(start 0.2794 -0.1778)
							(mid 0.249642 -0.249642)
							(end 0.1778 -0.2794)
						)
					)
					(width 0)
					(fill yes)
				)
			)
		)
	)
	(footprint ""
		(layer "F.Cu")
		(at 170.217084 -23.55977 90)
		(property "Reference" "VIA3"
			(at 0 0 90)
			(layer "F.SilkS")
			(hide yes)
			(effects
				(font
					(size 1.27 1.27)
				)
			)
		)
		(property "Value" "85OHM-8L-1D6MM-L16L18-GP"
			(at 4.064 0.6096 90)
			(unlocked yes)
			(layer "F.Fab")
			(hide yes)
			(effects
				(font
					(size 1.016 1.016)
					(thickness 0.1524)
				)
			)
		)
		(property "Device Type" "VIA-PCIE-4P-368076"
			(at 4.064 -0.9144 90)
			(unlocked yes)
			(layer "F.Fab")
			(hide yes)
			(effects
				(font
					(size 1.016 1.016)
					(thickness 0.1524)
				)
			)
		)
		(duplicate_pad_numbers_are_jumpers no)
		(fp_rect
			(start -1.8415 0.381)
			(end 1.8415 -0.381)
			(stroke
				(width 0)
				(type default)
			)
			(fill no)
			(layer "F.CrtYd")
		)
		(fp_rect
			(start -1.8415 0.381)
			(end 1.8415 -0.381)
			(stroke
				(width 0)
				(type default)
			)
			(fill no)
			(layer "F.Fab")
		)
		(pad "1" thru_hole circle
			(at -1.4605 0 90)
			(size 0.508 0.508)
			(drill 0.254)
			(layers "*.Cu" "*.Mask")
			(remove_unused_layers no)
			(net "GND")
			(clearance 0.127)
			(thermal_gap 0.127)
		)
		(pad "2" thru_hole circle
			(at -0.4445 0 90)
			(size 0.508 0.508)
			(drill 0.254)
			(layers "*.Cu" "*.Mask")
			(remove_unused_layers no)
			(net "PCIE_COMP_TO_SCC_2_DP")
			(clearance 0.127)
			(thermal_gap 0.127)
		)
		(pad "3" thru_hole circle
			(at 0.4445 0 90)
			(size 0.508 0.508)
			(drill 0.254)
			(layers "*.Cu" "*.Mask")
			(remove_unused_layers no)
			(net "PCIE_COMP_TO_SCC_2_DN")
			(clearance 0.127)
			(thermal_gap 0.127)
		)
		(pad "4" thru_hole circle
			(at 1.4605 0 90)
			(size 0.508 0.508)
			(drill 0.254)
			(layers "*.Cu" "*.Mask")
			(remove_unused_layers no)
			(net "GND")
			(clearance 0.127)
			(thermal_gap 0.127)
		)
	)
	(footprint ""
		(layer "F.Cu")
		(at 123.603258 -90.595196 180)
		(property "Reference" "R126"
			(at 0 0 180)
			(layer "F.SilkS")
			(hide yes)
			(effects
				(font
					(size 1.27 1.27)
				)
			)
		)
		(property "Value" "4K7R2F-GP"
			(at 0.064008 -3.993896 180)
			(unlocked yes)
			(layer "F.Fab")
			(hide yes)
			(effects
				(font
					(size 1.016 1.016)
					(thickness 0.1524)
				)
			)
		)
		(property "Device Type" "R402H16"
			(at 0.064008 -5.517896 180)
			(unlocked yes)
			(layer "F.Fab")
			(hide yes)
			(effects
				(font
					(size 1.016 1.016)
					(thickness 0.1524)
				)
			)
		)
		(duplicate_pad_numbers_are_jumpers no)
		(fp_line
			(start 0.508 -0.9398)
			(end -0.508 -0.9398)
			(stroke
				(width 0.1524)
				(type default)
			)
			(layer "F.SilkS")
		)
		(fp_line
			(start -0.508 -0.9398)
			(end -0.508 0.9398)
			(stroke
				(width 0.1524)
				(type default)
			)
			(layer "F.SilkS")
		)
		(fp_rect
			(start -0.508 0.9398)
			(end 0.508 -0.9398)
			(stroke
				(width 0)
				(type default)
			)
			(fill no)
			(layer "F.CrtYd")
		)
		(fp_rect
			(start -0.508 0.9398)
			(end 0.508 -0.9398)
			(stroke
				(width 0)
				(type default)
			)
			(fill no)
			(layer "F.Fab")
		)
		(pad "1" smd custom
			(at 0 -0.4445 180)
			(size 0.1397 0.1397)
			(layers "F.Cu" "F.Mask" "F.Paste")
			(net "USB_CLK")
			(options
				(clearance outline)
				(anchor circle)
			)
			(primitives
				(gr_poly
					(pts
						(arc
							(start -0.1778 -0.2794)
							(mid -0.249642 -0.249642)
							(end -0.2794 -0.1778)
						)
						(arc
							(start -0.2794 0.1778)
							(mid -0.249642 0.249642)
							(end -0.1778 0.2794)
						)
						(arc
							(start 0.1778 0.2794)
							(mid 0.249642 0.249642)
							(end 0.2794 0.1778)
						)
						(arc
							(start 0.2794 -0.1778)
							(mid 0.249642 -0.249642)
							(end 0.1778 -0.2794)
						)
					)
					(width 0)
					(fill yes)
				)
			)
		)
		(pad "2" smd custom
			(at 0 0.4445 180)
			(size 0.1397 0.1397)
			(layers "F.Cu" "F.Mask" "F.Paste")
			(net "GND")
			(options
				(clearance outline)
				(anchor circle)
			)
			(primitives
				(gr_poly
					(pts
						(arc
							(start -0.1778 -0.2794)
							(mid -0.249642 -0.249642)
							(end -0.2794 -0.1778)
						)
						(arc
							(start -0.2794 0.1778)
							(mid -0.249642 0.249642)
							(end -0.1778 0.2794)
						)
						(arc
							(start 0.1778 0.2794)
							(mid 0.249642 0.249642)
							(end 0.2794 0.1778)
						)
						(arc
							(start 0.2794 -0.1778)
							(mid 0.249642 -0.249642)
							(end 0.1778 -0.2794)
						)
					)
					(width 0)
					(fill yes)
				)
			)
		)
	)
	(footprint ""
		(layer "F.Cu")
		(at 135.975344 -84.714588)
		(property "Reference" "R61"
			(at 0 0 0)
			(layer "F.SilkS")
			(hide yes)
			(effects
				(font
					(size 1.27 1.27)
				)
			)
		)
		(property "Value" "4K7R2F-GP"
			(at 0.064008 -3.993896 0)
			(unlocked yes)
			(layer "F.Fab")
			(hide yes)
			(effects
				(font
					(size 1.016 1.016)
					(thickness 0.1524)
				)
			)
		)
		(property "Device Type" "R402H16"
			(at 0.064008 -5.517896 0)
			(unlocked yes)
			(layer "F.Fab")
			(hide yes)
			(effects
				(font
					(size 1.016 1.016)
					(thickness 0.1524)
				)
			)
		)
		(duplicate_pad_numbers_are_jumpers no)
		(fp_line
			(start -0.508 -0.9398)
			(end -0.508 0.9398)
			(stroke
				(width 0.1524)
				(type default)
			)
			(layer "F.SilkS")
		)
		(fp_line
			(start 0.508 -0.9398)
			(end -0.508 -0.9398)
			(stroke
				(width 0.1524)
				(type default)
			)
			(layer "F.SilkS")
		)
		(fp_rect
			(start -0.508 0.9398)
			(end 0.508 -0.9398)
			(stroke
				(width 0)
				(type default)
			)
			(fill no)
			(layer "F.CrtYd")
		)
		(fp_rect
			(start -0.508 0.9398)
			(end 0.508 -0.9398)
			(stroke
				(width 0)
				(type default)
			)
			(fill no)
			(layer "F.Fab")
		)
		(pad "1" smd custom
			(at 0 -0.4445)
			(size 0.1397 0.1397)
			(layers "F.Cu" "F.Mask" "F.Paste")
			(net "P1V8_E")
			(options
				(clearance outline)
				(anchor circle)
			)
			(primitives
				(gr_poly
					(pts
						(arc
							(start -0.1778 -0.2794)
							(mid -0.249642 -0.249642)
							(end -0.2794 -0.1778)
						)
						(arc
							(start -0.2794 0.1778)
							(mid -0.249642 0.249642)
							(end -0.1778 0.2794)
						)
						(arc
							(start 0.1778 0.2794)
							(mid 0.249642 0.249642)
							(end 0.2794 0.1778)
						)
						(arc
							(start 0.2794 -0.1778)
							(mid 0.249642 -0.249642)
							(end 0.1778 -0.2794)
						)
					)
					(width 0)
					(fill yes)
				)
			)
		)
		(pad "2" smd custom
			(at 0 0.4445)
			(size 0.1397 0.1397)
			(layers "F.Cu" "F.Mask" "F.Paste")
			(net "I2C_DRIVE_FLT_LED_SDA6_LS")
			(options
				(clearance outline)
				(anchor circle)
			)
			(primitives
				(gr_poly
					(pts
						(arc
							(start -0.1778 -0.2794)
							(mid -0.249642 -0.249642)
							(end -0.2794 -0.1778)
						)
						(arc
							(start -0.2794 0.1778)
							(mid -0.249642 0.249642)
							(end -0.1778 0.2794)
						)
						(arc
							(start 0.1778 0.2794)
							(mid 0.249642 0.249642)
							(end 0.2794 0.1778)
						)
						(arc
							(start 0.2794 -0.1778)
							(mid 0.249642 -0.249642)
							(end 0.1778 -0.2794)
						)
					)
					(width 0)
					(fill yes)
				)
			)
		)
	)
	(footprint ""
		(layer "F.Cu")
		(at 175.317404 -88.333834 90)
		(property "Reference" "L33"
			(at 0 0 90)
			(layer "F.SilkS")
			(hide yes)
			(effects
				(font
					(size 1.27 1.27)
				)
			)
		)
		(property "Value" "COIL-D24UH-GP"
			(at -5.5118 1.5748 90)
			(unlocked yes)
			(layer "F.Fab")
			(hide yes)
			(effects
				(font
					(size 1.016 1.016)
					(thickness 0.1524)
				)
			)
		)
		(property "Device Type" "L7267-1630H158"
			(at -5.5118 0.0508 90)
			(unlocked yes)
			(layer "F.Fab")
			(hide yes)
			(effects
				(font
					(size 1.016 1.016)
					(thickness 0.1524)
				)
			)
		)
		(duplicate_pad_numbers_are_jumpers no)
		(fp_line
			(start 3.6068 -4.6101)
			(end 3.6068 4.6101)
			(stroke
				(width 0.1524)
				(type default)
			)
			(layer "F.SilkS")
		)
		(fp_line
			(start -3.6068 -4.6101)
			(end 3.6068 -4.6101)
			(stroke
				(width 0.1524)
				(type default)
			)
			(layer "F.SilkS")
		)
		(fp_line
			(start 3.6068 4.6101)
			(end -3.6068 4.6101)
			(stroke
				(width 0.1524)
				(type default)
			)
			(layer "F.SilkS")
		)
		(fp_line
			(start -3.6068 4.6101)
			(end -3.6068 -4.6101)
			(stroke
				(width 0.1524)
				(type default)
			)
			(layer "F.SilkS")
		)
		(fp_rect
			(start -3.3528 3.5941)
			(end 3.3528 -3.5941)
			(stroke
				(width 0)
				(type default)
			)
			(fill no)
			(layer "F.CrtYd")
		)
		(fp_poly
			(pts
				(xy -3.8608 4.6863) (xy -3.8608 3.5941) (xy 3.3528 3.5941) (xy 3.3528 -3.5941) (xy -3.3528 -3.5941)
				(xy -3.3528 3.5814) (xy -3.8608 3.5814) (xy -3.8608 -4.6863) (xy 3.8608 -4.6863) (xy 3.8608 4.6863)
			)
			(stroke
				(width 0)
				(type default)
			)
			(fill no)
			(layer "F.CrtYd")
		)
		(fp_rect
			(start -3.8608 4.6863)
			(end 3.8608 -4.6863)
			(stroke
				(width 0)
				(type default)
			)
			(fill no)
			(layer "F.Fab")
		)
		(pad "1" smd rect
			(at 0 -2.990596 90)
			(size 3.5052 2.7432)
			(layers "F.Cu" "F.Mask" "F.Paste")
			(net "VT235_VX")
		)
		(pad "2" smd rect
			(at 0 2.990596 90)
			(size 3.5052 2.7432)
			(layers "F.Cu" "F.Mask" "F.Paste")
			(net "P0V975")
		)
	)
	(footprint ""
		(layer "F.Cu")
		(at 149.95906 -37.995352 102)
		(property "Reference" "C332"
			(at 0 0 102)
			(layer "F.SilkS")
			(hide yes)
			(effects
				(font
					(size 1.27 1.27)
				)
			)
		)
		(property "Value" "SCD01U16V1KX-GP"
			(at -2.832296 -1.73983 102)
			(unlocked yes)
			(layer "F.Fab")
			(hide yes)
			(effects
				(font
					(size 1.016 1.016)
					(thickness 0.1524)
				)
			)
		)
		(property "Device Type" "C0201H13"
			(at -2.832174 -3.263834 102)
			(unlocked yes)
			(layer "F.Fab")
			(hide yes)
			(effects
				(font
					(size 1.016 1.016)
					(thickness 0.1524)
				)
			)
		)
		(duplicate_pad_numbers_are_jumpers no)
		(fp_poly
			(pts
				(xy -0.279454 -0.647706) (xy 0.279346 -0.647706) (xy 0.279346 0.647694) (xy -0.279454 0.647694)
			)
			(stroke
				(width 0)
				(type default)
			)
			(fill no)
			(layer "F.CrtYd")
		)
		(fp_poly
			(pts
				(xy -0.279454 -0.647706) (xy 0.279346 -0.647706) (xy 0.279346 0.647694) (xy -0.279454 0.647694)
			)
			(stroke
				(width 0)
				(type default)
			)
			(fill no)
			(layer "F.Fab")
		)
		(pad "1" smd custom
			(at -0.000001 -0.2794 102)
			(size 0.0762 0.0762)
			(layers "F.Cu" "F.Mask" "F.Paste")
			(net "PHY_SCC_TO_IOC_42_DN")
			(options
				(clearance outline)
				(anchor circle)
			)
			(primitives
				(gr_poly
					(pts
						(arc
							(start 0.1524 -0.127)
							(mid 0.137521 -0.162921)
							(end 0.1016 -0.1778)
						)
						(arc
							(start -0.1016 -0.1778)
							(mid -0.137521 -0.162921)
							(end -0.1524 -0.127)
						)
						(arc
							(start -0.1524 0.127)
							(mid -0.137521 0.162921)
							(end -0.1016 0.1778)
						)
						(arc
							(start 0.1016 0.1778)
							(mid 0.137521 0.162921)
							(end 0.1524 0.127)
						)
					)
					(width 0)
					(fill yes)
				)
			)
		)
		(pad "2" smd custom
			(at 0.000001 0.2794 102)
			(size 0.0762 0.0762)
			(layers "F.Cu" "F.Mask" "F.Paste")
			(net "PHY_SCC_TO_IOC_C_42_DN")
			(options
				(clearance outline)
				(anchor circle)
			)
			(primitives
				(gr_poly
					(pts
						(arc
							(start 0.1524 -0.127)
							(mid 0.137521 -0.162921)
							(end 0.1016 -0.1778)
						)
						(arc
							(start -0.1016 -0.1778)
							(mid -0.137521 -0.162921)
							(end -0.1524 -0.127)
						)
						(arc
							(start -0.1524 0.127)
							(mid -0.137521 0.162921)
							(end -0.1016 0.1778)
						)
						(arc
							(start 0.1016 0.1778)
							(mid 0.137521 0.162921)
							(end 0.1524 0.127)
						)
					)
					(width 0)
					(fill yes)
				)
			)
		)
	)
)
